# T6G (Grand Teton) — schematic netlist excerpt (pin names and nets, part order shuffled) for the footprints in the layout excerpt that follows; sources: Cadence DE-HDL packaged netlist, KiCad conversion of 04192023_DAF0TMB3IC0_F0TG_MB_C_brd_V02_OCP.brd

C6618  Q_CAP_DIFFBUS  DIFF BUS_0.22UF 6.3V 20% X6S  pkg C0201  page 308 : \1\ = P5E_CPU0_P3_TX_BUF_C_DN<10> ; \2\ = P5E_CPU0_P3_TX_BUF_DN<10>
R325  Q_RES  0 5% CHIP  pkg 0402LF  page 161 : A = SMB_CPU0_CPU1_APML_SCL_R2 ; B = SMB_CPU0_CPU1_APML_MUX2_SCL
PC1751  Q_CAP  1NF 50V 10% EMPTY  pkg 0402  page 266 : A = P12V_HSC_GATE_RC ; B = P12V_HSC_GATE2

(kicad_pcb
	(version 20260206)
	(generator "pcbnew")
	(generator_version "10.0")
	(general
		(thickness 1.6)
		(legacy_teardrops no)
	)
	(paper "A4")
	(title_block
		(title "04192023_DAF0TMB3IC0_F0TG_MB_C_brd_V02_OCP.brd")
		(comment 1 "Grand Teton / footprints 4971-4973 of 8354")
	)
	(layers
		(0 "F.Cu" signal "TOP")
		(4 "In1.Cu" signal "GND")
		(6 "In2.Cu" signal "IN1")
		(8 "In3.Cu" signal "GND1")
		(10 "In4.Cu" signal "IN2")
		(12 "In5.Cu" signal "GND2")
		(14 "In6.Cu" signal "IN3")
		(16 "In7.Cu" signal "GND3")
		(18 "In8.Cu" signal "VCC")
		(20 "In9.Cu" signal "VCC1")
		(22 "In10.Cu" signal "GND4")
		(24 "In11.Cu" signal "IN4")
		(26 "In12.Cu" signal "GND5")
		(28 "In13.Cu" signal "IN5")
		(30 "In14.Cu" signal "GND6")
		(32 "In15.Cu" signal "IN6")
		(34 "In16.Cu" signal "GND7")
		(2 "B.Cu" signal "BOTTOM")
		(9 "F.Adhes" user "F.Adhesive")
		(11 "B.Adhes" user "B.Adhesive")
		(13 "F.Paste" user "Package Geometry/Pastemask Top")
		(15 "B.Paste" user "Package Geometry/Pastemask Bottom")
		(5 "F.SilkS" user "Ref Des/Silkscreen Top")
		(7 "B.SilkS" user "Ref Des/Silkscreen Bottom")
		(1 "F.Mask" user "Board Geometry/Soldermask Top")
		(3 "B.Mask" user "Board Geometry/Soldermask Bottom")
		(17 "Dwgs.User" user "User.Drawings")
		(19 "Cmts.User" user "User.Comments")
		(21 "Eco1.User" user "User.Eco1")
		(23 "Eco2.User" user "User.Eco2")
		(25 "Edge.Cuts" user "Board Geometry/Outline")
		(27 "Margin" user)
		(31 "F.CrtYd" user "Package Geometry/Place Bound Top")
		(29 "B.CrtYd" user "Package Geometry/Place Bound Bottom")
		(35 "F.Fab" user "Ref Des/Assembly Top")
		(33 "B.Fab" user "Ref Des/Assembly Bottom")
	)
	(footprint ""
		(layer "B.Cu")
		(at 244.099842 -382.936242 90)
		(property "Reference" "PC1751"
			(at 0 0 90)
			(layer "B.SilkS")
			(hide yes)
			(effects
				(font
					(size 1.27 1.27)
				)
				(justify mirror)
			)
		)
		(property "Value" ""
			(at 0 0 90)
			(layer "B.Fab")
			(effects
				(font
					(size 1.27 1.27)
				)
				(justify mirror)
			)
		)
		(duplicate_pad_numbers_are_jumpers no)
		(fp_line
			(start 0.7874 -0.4064)
			(end -0.7874 -0.4064)
			(stroke
				(width 0.1524)
				(type default)
			)
			(layer "B.SilkS")
		)
		(fp_line
			(start -0.7874 -0.4064)
			(end -0.7874 0.4064)
			(stroke
				(width 0.1524)
				(type default)
			)
			(layer "B.SilkS")
		)
		(fp_line
			(start 0.7874 0.4064)
			(end 0.7874 -0.4064)
			(stroke
				(width 0.1524)
				(type default)
			)
			(layer "B.SilkS")
		)
		(fp_line
			(start -0.7874 0.4064)
			(end 0.7874 0.4064)
			(stroke
				(width 0.1524)
				(type default)
			)
			(layer "B.SilkS")
		)
		(fp_line
			(start 0.67945 -0.305054)
			(end 0.12065 -0.305054)
			(stroke
				(width 0.1)
				(type default)
			)
			(layer "B.Fab")
		)
		(fp_line
			(start 0.12065 -0.305054)
			(end 0.12065 -0.2794)
			(stroke
				(width 0.1)
				(type default)
			)
			(layer "B.Fab")
		)
		(fp_line
			(start -0.12065 -0.3048)
			(end -0.67945 -0.3048)
			(stroke
				(width 0.1)
				(type default)
			)
			(layer "B.Fab")
		)
		(fp_line
			(start -0.67945 -0.3048)
			(end -0.67945 0.3048)
			(stroke
				(width 0.1)
				(type default)
			)
			(layer "B.Fab")
		)
		(fp_line
			(start 0.12065 -0.2794)
			(end -0.12065 -0.2794)
			(stroke
				(width 0.1)
				(type default)
			)
			(layer "B.Fab")
		)
		(fp_line
			(start -0.12065 -0.2794)
			(end -0.12065 -0.3048)
			(stroke
				(width 0.1)
				(type default)
			)
			(layer "B.Fab")
		)
		(fp_line
			(start 0.12065 0.2794)
			(end 0.12065 0.3048)
			(stroke
				(width 0.1)
				(type default)
			)
			(layer "B.Fab")
		)
		(fp_line
			(start -0.120396 0.2794)
			(end 0.12065 0.2794)
			(stroke
				(width 0.1)
				(type default)
			)
			(layer "B.Fab")
		)
		(fp_line
			(start 0.67945 0.3048)
			(end 0.67945 -0.305054)
			(stroke
				(width 0.1)
				(type default)
			)
			(layer "B.Fab")
		)
		(fp_line
			(start 0.12065 0.3048)
			(end 0.67945 0.3048)
			(stroke
				(width 0.1)
				(type default)
			)
			(layer "B.Fab")
		)
		(fp_line
			(start -0.120396 0.3048)
			(end -0.120396 0.2794)
			(stroke
				(width 0.1)
				(type default)
			)
			(layer "B.Fab")
		)
		(fp_line
			(start -0.67945 0.3048)
			(end -0.120396 0.3048)
			(stroke
				(width 0.1)
				(type default)
			)
			(layer "B.Fab")
		)
		(pad "1" smd circle
			(at 0.40005 0 270)
			(size 0 0)
			(layers "B.Cu" "B.Mask" "B.Paste")
			(net "P12V_HSC_GATE_RC")
		)
		(pad "2" smd circle
			(at -0.40005 0 270)
			(size 0 0)
			(layers "B.Cu" "B.Mask" "B.Paste")
			(net "P12V_HSC_GATE2")
		)
	)
	(footprint ""
		(layer "B.Cu")
		(at 231.775 -243.2431 -90)
		(property "Reference" "R325"
			(at 0 0 90)
			(layer "B.SilkS")
			(hide yes)
			(effects
				(font
					(size 1.27 1.27)
				)
				(justify mirror)
			)
		)
		(property "Value" ""
			(at 0 0 90)
			(layer "B.Fab")
			(effects
				(font
					(size 1.27 1.27)
				)
				(justify mirror)
			)
		)
		(duplicate_pad_numbers_are_jumpers no)
		(fp_line
			(start -0.7874 0.4064)
			(end 0.7874 0.4064)
			(stroke
				(width 0.1524)
				(type default)
			)
			(layer "B.SilkS")
		)
		(fp_line
			(start 0.7874 0.4064)
			(end 0.7874 -0.4064)
			(stroke
				(width 0.1524)
				(type default)
			)
			(layer "B.SilkS")
		)
		(fp_line
			(start -0.7874 -0.4064)
			(end -0.7874 0.4064)
			(stroke
				(width 0.1524)
				(type default)
			)
			(layer "B.SilkS")
		)
		(fp_line
			(start 0.7874 -0.4064)
			(end -0.7874 -0.4064)
			(stroke
				(width 0.1524)
				(type default)
			)
			(layer "B.SilkS")
		)
		(fp_line
			(start -0.67945 0.3048)
			(end -0.120396 0.3048)
			(stroke
				(width 0.1)
				(type default)
			)
			(layer "B.Fab")
		)
		(fp_line
			(start -0.120396 0.3048)
			(end -0.120396 0.2794)
			(stroke
				(width 0.1)
				(type default)
			)
			(layer "B.Fab")
		)
		(fp_line
			(start 0.12065 0.3048)
			(end 0.67945 0.3048)
			(stroke
				(width 0.1)
				(type default)
			)
			(layer "B.Fab")
		)
		(fp_line
			(start 0.67945 0.3048)
			(end 0.67945 -0.305054)
			(stroke
				(width 0.1)
				(type default)
			)
			(layer "B.Fab")
		)
		(fp_line
			(start -0.120396 0.2794)
			(end 0.12065 0.2794)
			(stroke
				(width 0.1)
				(type default)
			)
			(layer "B.Fab")
		)
		(fp_line
			(start 0.12065 0.2794)
			(end 0.12065 0.3048)
			(stroke
				(width 0.1)
				(type default)
			)
			(layer "B.Fab")
		)
		(fp_line
			(start -0.12065 -0.2794)
			(end -0.12065 -0.3048)
			(stroke
				(width 0.1)
				(type default)
			)
			(layer "B.Fab")
		)
		(fp_line
			(start 0.12065 -0.2794)
			(end -0.12065 -0.2794)
			(stroke
				(width 0.1)
				(type default)
			)
			(layer "B.Fab")
		)
		(fp_line
			(start -0.67945 -0.3048)
			(end -0.67945 0.3048)
			(stroke
				(width 0.1)
				(type default)
			)
			(layer "B.Fab")
		)
		(fp_line
			(start -0.12065 -0.3048)
			(end -0.67945 -0.3048)
			(stroke
				(width 0.1)
				(type default)
			)
			(layer "B.Fab")
		)
		(fp_line
			(start 0.12065 -0.305054)
			(end 0.12065 -0.2794)
			(stroke
				(width 0.1)
				(type default)
			)
			(layer "B.Fab")
		)
		(fp_line
			(start 0.67945 -0.305054)
			(end 0.12065 -0.305054)
			(stroke
				(width 0.1)
				(type default)
			)
			(layer "B.Fab")
		)
		(pad "1" smd rect
			(at 0.40005 0 270)
			(size 0.4572 0.508)
			(layers "B.Cu" "B.Mask" "B.Paste")
			(net "SMB_CPU0_CPU1_APML_SCL_R2")
		)
		(pad "2" smd rect
			(at -0.40005 0 270)
			(size 0.4572 0.508)
			(layers "B.Cu" "B.Mask" "B.Paste")
			(net "SMB_CPU0_CPU1_APML_MUX2_SCL")
		)
	)
	(footprint ""
		(layer "B.Cu")
		(at 403.032722 -416.899344 90)
		(property "Reference" "C6618"
			(at 0 0 90)
			(layer "B.SilkS")
			(hide yes)
			(effects
				(font
					(size 1.27 1.27)
				)
				(justify mirror)
			)
		)
		(property "Value" ""
			(at 0 0 90)
			(layer "B.Fab")
			(effects
				(font
					(size 1.27 1.27)
				)
				(justify mirror)
			)
		)
		(duplicate_pad_numbers_are_jumpers no)
		(fp_line
			(start 0.299974 -0.150114)
			(end -0.299974 -0.150114)
			(stroke
				(width 0.1)
				(type default)
			)
			(layer "B.Fab")
		)
		(fp_line
			(start -0.299974 -0.150114)
			(end -0.299974 0.150114)
			(stroke
				(width 0.1)
				(type default)
			)
			(layer "B.Fab")
		)
		(fp_line
			(start 0.299974 0.150114)
			(end 0.299974 -0.150114)
			(stroke
				(width 0.1)
				(type default)
			)
			(layer "B.Fab")
		)
		(fp_line
			(start -0.299974 0.150114)
			(end 0.299974 0.150114)
			(stroke
				(width 0.1)
				(type default)
			)
			(layer "B.Fab")
		)
		(pad "1" smd rect
			(at 0.2667 0 270)
			(size 0.3048 0.381)
			(layers "B.Cu" "B.Mask" "B.Paste")
			(net "P5E_CPU0_P3_TX_BUF_C_DN<10>")
		)
		(pad "2" smd rect
			(at -0.2667 0 270)
			(size 0.3048 0.381)
			(layers "B.Cu" "B.Mask" "B.Paste")
			(net "P5E_CPU0_P3_TX_BUF_DN<10>")
		)
	)
)
